(kicad_pcb
	(version 20260206)
	(generator "pcbnew")
	(generator_version "10.0")
	(general
		(thickness 1.6)
		(legacy_teardrops no)
	)
	(paper "A4")
	(title_block
		(title "v1-chassis-manager — T6M_CM_d_v01_1031_1645.brd")
		(comment 1 "Open CloudServer (Microsoft) / footprints 82-91 of 2512")
	)
	(layers
		(0 "F.Cu" signal "TOP")
		(4 "In1.Cu" signal "GND1")
		(6 "In2.Cu" signal "IN1")
		(8 "In3.Cu" signal "VCC1")
		(10 "In4.Cu" signal "VCC2")
		(12 "In5.Cu" signal "GND2")
		(14 "In6.Cu" signal "IN2")
		(16 "In7.Cu" signal "IN3")
		(18 "In8.Cu" signal "GND3")
		(2 "B.Cu" signal "BOTTOM")
		(9 "F.Adhes" user "F.Adhesive")
		(11 "B.Adhes" user "B.Adhesive")
		(13 "F.Paste" user "Package Geometry/Pastemask Top")
		(15 "B.Paste" user "Package Geometry/Pastemask Bottom")
		(5 "F.SilkS" user "Ref Des/Silkscreen Top")
		(7 "B.SilkS" user "Ref Des/Silkscreen Bottom")
		(1 "F.Mask" user "Board Geometry/Soldermask Top")
		(3 "B.Mask" user "Board Geometry/Soldermask Bottom")
		(17 "Dwgs.User" user "User.Drawings")
		(19 "Cmts.User" user "User.Comments")
		(21 "Eco1.User" user "User.Eco1")
		(23 "Eco2.User" user "User.Eco2")
		(25 "Edge.Cuts" user "Board Geometry/Outline")
		(27 "Margin" user)
		(31 "F.CrtYd" user "Package Geometry/Place Bound Top")
		(29 "B.CrtYd" user "Package Geometry/Place Bound Bottom")
		(35 "F.Fab" user "Ref Des/Assembly Top")
		(33 "B.Fab" user "Ref Des/Assembly Bottom")
	)
	(footprint ""
		(layer "F.Cu")
		(at 176.267364 -132.622798 -90)
		(property "Reference" "R1131"
			(at 2.232152 -12.395454 90)
			(unlocked yes)
			(layer "F.SilkS")
			(effects
				(font
					(size 0.7874 0.5842)
					(thickness 0.1524)
				)
				(justify left)
			)
		)
		(property "Value" ""
			(at 0 0 270)
			(layer "F.Fab")
			(effects
				(font
					(size 1.27 1.27)
				)
			)
		)
		(duplicate_pad_numbers_are_jumpers no)
		(fp_line
			(start -0.7874 0.4064)
			(end -0.7874 -0.4064)
			(stroke
				(width 0.1524)
				(type default)
			)
			(layer "F.SilkS")
		)
		(fp_line
			(start 0.7874 0.4064)
			(end -0.7874 0.4064)
			(stroke
				(width 0.1524)
				(type default)
			)
			(layer "F.SilkS")
		)
		(fp_line
			(start -0.7874 -0.4064)
			(end 0.7874 -0.4064)
			(stroke
				(width 0.1524)
				(type default)
			)
			(layer "F.SilkS")
		)
		(fp_line
			(start 0.7874 -0.4064)
			(end 0.7874 0.4064)
			(stroke
				(width 0.1524)
				(type default)
			)
			(layer "F.SilkS")
		)
		(fp_poly
			(pts
				(xy -0.508 0.2794) (xy -0.508 0.2286) (xy -0.635 0.2286) (xy -0.635 -0.254) (xy -0.5334 -0.254)
				(xy -0.5334 -0.2794) (xy 0.5334 -0.2794) (xy 0.5334 -0.254) (xy 0.635 -0.254) (xy 0.635 0.254) (xy 0.5334 0.254)
				(xy 0.5334 0.2794)
			)
			(stroke
				(width 0)
				(type default)
			)
			(fill no)
			(layer "F.CrtYd")
		)
		(pad "1" smd rect
			(at 0.40005 0 270)
			(size 0.4572 0.508)
			(layers "F.Cu" "F.Mask" "F.Paste")
			(net "CPLD_CPU_THRMTRIP_N")
		)
		(pad "2" smd rect
			(at -0.40005 0 270)
			(size 0.4572 0.508)
			(layers "F.Cu" "F.Mask" "F.Paste")
			(net "P3V3_STB_NODE1")
		)
	)
	(footprint ""
		(layer "F.Cu")
		(at 34.990786 -175.4505 90)
		(property "Reference" "R106"
			(at -10.50671 -3.513836 90)
			(unlocked yes)
			(layer "F.SilkS")
			(effects
				(font
					(size 0.7874 0.5842)
					(thickness 0.1524)
				)
				(justify left)
			)
		)
		(property "Value" ""
			(at 0 0 90)
			(layer "F.Fab")
			(effects
				(font
					(size 1.27 1.27)
				)
			)
		)
		(duplicate_pad_numbers_are_jumpers no)
		(fp_line
			(start 0.7874 -0.4064)
			(end 0.7874 0.4064)
			(stroke
				(width 0.1524)
				(type default)
			)
			(layer "F.SilkS")
		)
		(fp_line
			(start -0.7874 -0.4064)
			(end 0.7874 -0.4064)
			(stroke
				(width 0.1524)
				(type default)
			)
			(layer "F.SilkS")
		)
		(fp_line
			(start 0.7874 0.4064)
			(end -0.7874 0.4064)
			(stroke
				(width 0.1524)
				(type default)
			)
			(layer "F.SilkS")
		)
		(fp_line
			(start -0.7874 0.4064)
			(end -0.7874 -0.4064)
			(stroke
				(width 0.1524)
				(type default)
			)
			(layer "F.SilkS")
		)
		(fp_poly
			(pts
				(xy -0.508 0.2794) (xy -0.508 0.2286) (xy -0.635 0.2286) (xy -0.635 -0.254) (xy -0.5334 -0.254)
				(xy -0.5334 -0.2794) (xy 0.5334 -0.2794) (xy 0.5334 -0.254) (xy 0.635 -0.254) (xy 0.635 0.254) (xy 0.5334 0.254)
				(xy 0.5334 0.2794)
			)
			(stroke
				(width 0)
				(type default)
			)
			(fill no)
			(layer "F.CrtYd")
		)
		(pad "1" smd rect
			(at 0.40005 0 90)
			(size 0.4572 0.508)
			(layers "F.Cu" "F.Mask" "F.Paste")
			(net "SMB_BMC_NODE1_HSC_ALERT_R_L")
		)
		(pad "2" smd rect
			(at -0.40005 0 90)
			(size 0.4572 0.508)
			(layers "F.Cu" "F.Mask" "F.Paste")
			(net "SMB_BMC_NODE1_HSC_ALERT_L")
		)
	)
	(footprint ""
		(layer "F.Cu")
		(at 56.884062 -118.971568 -90)
		(property "Reference" "R344"
			(at 5.201412 -1.117092 90)
			(unlocked yes)
			(layer "F.SilkS")
			(effects
				(font
					(size 0.7874 0.5842)
					(thickness 0.1524)
				)
				(justify left)
			)
		)
		(property "Value" ""
			(at 0 0 270)
			(layer "F.Fab")
			(effects
				(font
					(size 1.27 1.27)
				)
			)
		)
		(duplicate_pad_numbers_are_jumpers no)
		(fp_line
			(start -0.7874 0.4064)
			(end -0.7874 -0.4064)
			(stroke
				(width 0.1524)
				(type default)
			)
			(layer "F.SilkS")
		)
		(fp_line
			(start 0.7874 0.4064)
			(end -0.7874 0.4064)
			(stroke
				(width 0.1524)
				(type default)
			)
			(layer "F.SilkS")
		)
		(fp_line
			(start -0.7874 -0.4064)
			(end 0.7874 -0.4064)
			(stroke
				(width 0.1524)
				(type default)
			)
			(layer "F.SilkS")
		)
		(fp_line
			(start 0.7874 -0.4064)
			(end 0.7874 0.4064)
			(stroke
				(width 0.1524)
				(type default)
			)
			(layer "F.SilkS")
		)
		(fp_poly
			(pts
				(xy -0.508 0.2794) (xy -0.508 0.2286) (xy -0.635 0.2286) (xy -0.635 -0.254) (xy -0.5334 -0.254)
				(xy -0.5334 -0.2794) (xy 0.5334 -0.2794) (xy 0.5334 -0.254) (xy 0.635 -0.254) (xy 0.635 0.254) (xy 0.5334 0.254)
				(xy 0.5334 0.2794)
			)
			(stroke
				(width 0)
				(type default)
			)
			(fill no)
			(layer "F.CrtYd")
		)
		(pad "1" smd rect
			(at 0.40005 0 270)
			(size 0.4572 0.508)
			(layers "F.Cu" "F.Mask" "F.Paste")
			(net "P3V3_NODE1")
		)
		(pad "2" smd rect
			(at -0.40005 0 270)
			(size 0.4572 0.508)
			(layers "F.Cu" "F.Mask" "F.Paste")
			(net "BMC_ROMD4")
		)
	)
	(footprint ""
		(layer "F.Cu")
		(at 114.13109 -63.348616 180)
		(property "Reference" "C183"
			(at -1.060196 -1.891792 0)
			(unlocked yes)
			(layer "F.SilkS")
			(effects
				(font
					(size 0.7874 0.5842)
					(thickness 0.1524)
				)
				(justify left)
			)
		)
		(property "Value" ""
			(at 0 0 180)
			(layer "F.Fab")
			(effects
				(font
					(size 1.27 1.27)
				)
			)
		)
		(duplicate_pad_numbers_are_jumpers no)
		(fp_line
			(start 0.7874 0.4064)
			(end -0.7874 0.4064)
			(stroke
				(width 0.1524)
				(type default)
			)
			(layer "F.SilkS")
		)
		(fp_line
			(start 0.7874 -0.4064)
			(end 0.7874 0.4064)
			(stroke
				(width 0.1524)
				(type default)
			)
			(layer "F.SilkS")
		)
		(fp_line
			(start 0 0.381)
			(end 0 -0.381)
			(stroke
				(width 0.1524)
				(type default)
			)
			(layer "F.SilkS")
		)
		(fp_line
			(start -0.7874 0.4064)
			(end -0.7874 -0.4064)
			(stroke
				(width 0.1524)
				(type default)
			)
			(layer "F.SilkS")
		)
		(fp_line
			(start -0.7874 -0.4064)
			(end 0.7874 -0.4064)
			(stroke
				(width 0.1524)
				(type default)
			)
			(layer "F.SilkS")
		)
		(fp_poly
			(pts
				(xy -0.5334 0.254) (xy -0.635 0.254) (xy -0.635 0.2286) (xy -0.635 -0.254) (xy -0.5334 -0.254) (xy -0.5334 -0.2794)
				(xy 0.5334 -0.2794) (xy 0.5334 -0.254) (xy 0.635 -0.254) (xy 0.635 0.254) (xy 0.5334 0.254) (xy 0.5334 0.2794)
				(xy -0.508 0.2794) (xy -0.5334 0.2794)
			)
			(stroke
				(width 0)
				(type default)
			)
			(fill no)
			(layer "F.CrtYd")
		)
		(pad "1" smd rect
			(at 0.40005 0 180)
			(size 0.4572 0.508)
			(layers "F.Cu" "F.Mask" "F.Paste")
			(net "RST_NODE1_CPU_XDP_RSTIN_L")
		)
		(pad "2" smd rect
			(at -0.40005 0 180)
			(size 0.4572 0.508)
			(layers "F.Cu" "F.Mask" "F.Paste")
			(net "GND")
		)
	)
	(footprint ""
		(layer "F.Cu")
		(at 81.06029 -151.304498 90)
		(property "Reference" "R1083"
			(at -2.23393 -0.85979 0)
			(unlocked yes)
			(layer "F.SilkS")
			(effects
				(font
					(size 0.7874 0.5842)
					(thickness 0.1524)
				)
				(justify left)
			)
		)
		(property "Value" ""
			(at 0 0 90)
			(layer "F.Fab")
			(effects
				(font
					(size 1.27 1.27)
				)
			)
		)
		(duplicate_pad_numbers_are_jumpers no)
		(fp_line
			(start 0.7874 -0.4064)
			(end 0.7874 0.4064)
			(stroke
				(width 0.1524)
				(type default)
			)
			(layer "F.SilkS")
		)
		(fp_line
			(start -0.7874 -0.4064)
			(end 0.7874 -0.4064)
			(stroke
				(width 0.1524)
				(type default)
			)
			(layer "F.SilkS")
		)
		(fp_line
			(start 0.7874 0.4064)
			(end -0.7874 0.4064)
			(stroke
				(width 0.1524)
				(type default)
			)
			(layer "F.SilkS")
		)
		(fp_line
			(start -0.7874 0.4064)
			(end -0.7874 -0.4064)
			(stroke
				(width 0.1524)
				(type default)
			)
			(layer "F.SilkS")
		)
		(fp_poly
			(pts
				(xy -0.508 0.2794) (xy -0.508 0.2286) (xy -0.635 0.2286) (xy -0.635 -0.254) (xy -0.5334 -0.254)
				(xy -0.5334 -0.2794) (xy 0.5334 -0.2794) (xy 0.5334 -0.254) (xy 0.635 -0.254) (xy 0.635 0.254) (xy 0.5334 0.254)
				(xy 0.5334 0.2794)
			)
			(stroke
				(width 0)
				(type default)
			)
			(fill no)
			(layer "F.CrtYd")
		)
		(pad "1" smd rect
			(at 0.40005 0 90)
			(size 0.4572 0.508)
			(layers "F.Cu" "F.Mask" "F.Paste")
			(net "P5V_STB_NODE1_EN")
		)
		(pad "2" smd rect
			(at -0.40005 0 90)
			(size 0.4572 0.508)
			(layers "F.Cu" "F.Mask" "F.Paste")
			(net "GND")
		)
	)
	(footprint ""
		(layer "F.Cu")
		(at 106.170476 -169.932858 180)
		(property "Reference" "R761"
			(at -1.206754 -0.161798 0)
			(unlocked yes)
			(layer "F.SilkS")
			(effects
				(font
					(size 0.7874 0.5842)
					(thickness 0.1524)
				)
				(justify left)
			)
		)
		(property "Value" ""
			(at 0 0 180)
			(layer "F.Fab")
			(effects
				(font
					(size 1.27 1.27)
				)
			)
		)
		(duplicate_pad_numbers_are_jumpers no)
		(fp_line
			(start 0.7874 0.4064)
			(end -0.7874 0.4064)
			(stroke
				(width 0.1524)
				(type default)
			)
			(layer "F.SilkS")
		)
		(fp_line
			(start 0.7874 -0.4064)
			(end 0.7874 0.4064)
			(stroke
				(width 0.1524)
				(type default)
			)
			(layer "F.SilkS")
		)
		(fp_line
			(start -0.7874 0.4064)
			(end -0.7874 -0.4064)
			(stroke
				(width 0.1524)
				(type default)
			)
			(layer "F.SilkS")
		)
		(fp_line
			(start -0.7874 -0.4064)
			(end 0.7874 -0.4064)
			(stroke
				(width 0.1524)
				(type default)
			)
			(layer "F.SilkS")
		)
		(fp_poly
			(pts
				(xy -0.508 0.2794) (xy -0.508 0.2286) (xy -0.635 0.2286) (xy -0.635 -0.254) (xy -0.5334 -0.254)
				(xy -0.5334 -0.2794) (xy 0.5334 -0.2794) (xy 0.5334 -0.254) (xy 0.635 -0.254) (xy 0.635 0.254) (xy 0.5334 0.254)
				(xy 0.5334 0.2794)
			)
			(stroke
				(width 0)
				(type default)
			)
			(fill no)
			(layer "F.CrtYd")
		)
		(pad "1" smd rect
			(at 0.40005 0 180)
			(size 0.4572 0.508)
			(layers "F.Cu" "F.Mask" "F.Paste")
			(net "FAN4_TACH_IN")
		)
		(pad "2" smd rect
			(at -0.40005 0 180)
			(size 0.4572 0.508)
			(layers "F.Cu" "F.Mask" "F.Paste")
			(net "FAN4_TACH")
		)
	)
	(footprint ""
		(layer "F.Cu")
		(at 64.628522 -158.423864)
		(property "Reference" "PC132"
			(at -32.07639 -3.594354 0)
			(unlocked yes)
			(layer "F.SilkS")
			(effects
				(font
					(size 0.7874 0.5842)
					(thickness 0.1524)
				)
				(justify left)
			)
		)
		(property "Value" ""
			(at 0 0 0)
			(layer "F.Fab")
			(effects
				(font
					(size 1.27 1.27)
				)
			)
		)
		(duplicate_pad_numbers_are_jumpers no)
		(fp_line
			(start -1.905 -0.8636)
			(end 1.905 -0.8636)
			(stroke
				(width 0.1524)
				(type default)
			)
			(layer "F.SilkS")
		)
		(fp_line
			(start -1.905 0.8636)
			(end -1.905 -0.8636)
			(stroke
				(width 0.1524)
				(type default)
			)
			(layer "F.SilkS")
		)
		(fp_line
			(start 0 0.8382)
			(end 0 -0.8382)
			(stroke
				(width 0.1524)
				(type default)
			)
			(layer "F.SilkS")
		)
		(fp_line
			(start 1.905 -0.8636)
			(end 1.905 0.8636)
			(stroke
				(width 0.1524)
				(type default)
			)
			(layer "F.SilkS")
		)
		(fp_line
			(start 1.905 0.8636)
			(end -1.905 0.8636)
			(stroke
				(width 0.1524)
				(type default)
			)
			(layer "F.SilkS")
		)
		(fp_rect
			(start -1.524 0.7366)
			(end 1.524 -0.7366)
			(stroke
				(width 0)
				(type default)
			)
			(fill no)
			(layer "F.CrtYd")
		)
		(pad "1" smd rect
			(at 0.94996 0)
			(size 1.1176 1.3716)
			(layers "F.Cu" "F.Mask" "F.Paste")
			(net "P5V_STB_NODE1")
		)
		(pad "2" smd rect
			(at -0.94996 0)
			(size 1.1176 1.3716)
			(layers "F.Cu" "F.Mask" "F.Paste")
			(net "GND")
		)
	)
	(footprint ""
		(layer "F.Cu")
		(at 184.3786 -183.8452)
		(property "Reference" "R1319"
			(at 9.398 17.01927 0)
			(unlocked yes)
			(layer "F.SilkS")
			(effects
				(font
					(size 0.7874 0.5842)
					(thickness 0.1524)
				)
				(justify left)
			)
		)
		(property "Value" ""
			(at 0 0 0)
			(layer "F.Fab")
			(effects
				(font
					(size 1.27 1.27)
				)
			)
		)
		(duplicate_pad_numbers_are_jumpers no)
		(fp_line
			(start -0.7874 -0.4064)
			(end 0.7874 -0.4064)
			(stroke
				(width 0.1524)
				(type default)
			)
			(layer "F.SilkS")
		)
		(fp_line
			(start -0.7874 0.4064)
			(end -0.7874 -0.4064)
			(stroke
				(width 0.1524)
				(type default)
			)
			(layer "F.SilkS")
		)
		(fp_line
			(start 0.7874 -0.4064)
			(end 0.7874 0.4064)
			(stroke
				(width 0.1524)
				(type default)
			)
			(layer "F.SilkS")
		)
		(fp_line
			(start 0.7874 0.4064)
			(end -0.7874 0.4064)
			(stroke
				(width 0.1524)
				(type default)
			)
			(layer "F.SilkS")
		)
		(fp_poly
			(pts
				(xy -0.508 0.2794) (xy -0.508 0.2286) (xy -0.635 0.2286) (xy -0.635 -0.254) (xy -0.5334 -0.254)
				(xy -0.5334 -0.2794) (xy 0.5334 -0.2794) (xy 0.5334 -0.254) (xy 0.635 -0.254) (xy 0.635 0.254) (xy 0.5334 0.254)
				(xy 0.5334 0.2794)
			)
			(stroke
				(width 0)
				(type default)
			)
			(fill no)
			(layer "F.CrtYd")
		)
		(pad "1" smd rect
			(at 0.40005 0)
			(size 0.4572 0.508)
			(layers "F.Cu" "F.Mask" "F.Paste")
			(net "POWER_SW3_PWR_CTR_12V")
		)
		(pad "2" smd rect
			(at -0.40005 0)
			(size 0.4572 0.508)
			(layers "F.Cu" "F.Mask" "F.Paste")
			(net "POWER_SW3_PWR_CTR_12V_R")
		)
	)
	(footprint ""
		(layer "F.Cu")
		(at 82.7278 -85.439504 -90)
		(property "Reference" "C25"
			(at 17.558512 -1.900174 90)
			(unlocked yes)
			(layer "F.SilkS")
			(effects
				(font
					(size 0.7874 0.5842)
					(thickness 0.1524)
				)
				(justify left)
			)
		)
		(property "Value" ""
			(at 0 0 270)
			(layer "F.Fab")
			(effects
				(font
					(size 1.27 1.27)
				)
			)
		)
		(duplicate_pad_numbers_are_jumpers no)
		(fp_line
			(start -0.7874 0.4064)
			(end -0.7874 -0.4064)
			(stroke
				(width 0.1524)
				(type default)
			)
			(layer "F.SilkS")
		)
		(fp_line
			(start 0.7874 0.4064)
			(end -0.7874 0.4064)
			(stroke
				(width 0.1524)
				(type default)
			)
			(layer "F.SilkS")
		)
		(fp_line
			(start 0 0.381)
			(end 0 -0.381)
			(stroke
				(width 0.1524)
				(type default)
			)
			(layer "F.SilkS")
		)
		(fp_line
			(start -0.7874 -0.4064)
			(end 0.7874 -0.4064)
			(stroke
				(width 0.1524)
				(type default)
			)
			(layer "F.SilkS")
		)
		(fp_line
			(start 0.7874 -0.4064)
			(end 0.7874 0.4064)
			(stroke
				(width 0.1524)
				(type default)
			)
			(layer "F.SilkS")
		)
		(fp_poly
			(pts
				(xy -0.5334 0.254) (xy -0.635 0.254) (xy -0.635 0.2286) (xy -0.635 -0.254) (xy -0.5334 -0.254) (xy -0.5334 -0.2794)
				(xy 0.5334 -0.2794) (xy 0.5334 -0.254) (xy 0.635 -0.254) (xy 0.635 0.254) (xy 0.5334 0.254) (xy 0.5334 0.2794)
				(xy -0.508 0.2794) (xy -0.5334 0.2794)
			)
			(stroke
				(width 0)
				(type default)
			)
			(fill no)
			(layer "F.CrtYd")
		)
		(pad "1" smd rect
			(at 0.40005 0 270)
			(size 0.4572 0.508)
			(layers "F.Cu" "F.Mask" "F.Paste")
			(net "XTAL_CPU_NODE1_X2PAD")
		)
		(pad "2" smd rect
			(at -0.40005 0 270)
			(size 0.4572 0.508)
			(layers "F.Cu" "F.Mask" "F.Paste")
			(net "GND")
		)
	)
	(footprint ""
		(layer "F.Cu")
		(at 94.451932 -170.219624)
		(property "Reference" "R756"
			(at 86.67369 74.174096 0)
			(unlocked yes)
			(layer "F.SilkS")
			(effects
				(font
					(size 0.7874 0.5842)
					(thickness 0.1524)
				)
				(justify left)
			)
		)
		(property "Value" ""
			(at 0 0 0)
			(layer "F.Fab")
			(effects
				(font
					(size 1.27 1.27)
				)
			)
		)
		(duplicate_pad_numbers_are_jumpers no)
		(fp_line
			(start -0.7874 -0.4064)
			(end 0.7874 -0.4064)
			(stroke
				(width 0.1524)
				(type default)
			)
			(layer "F.SilkS")
		)
		(fp_line
			(start -0.7874 0.4064)
			(end -0.7874 -0.4064)
			(stroke
				(width 0.1524)
				(type default)
			)
			(layer "F.SilkS")
		)
		(fp_line
			(start 0.7874 -0.4064)
			(end 0.7874 0.4064)
			(stroke
				(width 0.1524)
				(type default)
			)
			(layer "F.SilkS")
		)
		(fp_line
			(start 0.7874 0.4064)
			(end -0.7874 0.4064)
			(stroke
				(width 0.1524)
				(type default)
			)
			(layer "F.SilkS")
		)
		(fp_poly
			(pts
				(xy -0.508 0.2794) (xy -0.508 0.2286) (xy -0.635 0.2286) (xy -0.635 -0.254) (xy -0.5334 -0.254)
				(xy -0.5334 -0.2794) (xy 0.5334 -0.2794) (xy 0.5334 -0.254) (xy 0.635 -0.254) (xy 0.635 0.254) (xy 0.5334 0.254)
				(xy 0.5334 0.2794)
			)
			(stroke
				(width 0)
				(type default)
			)
			(fill no)
			(layer "F.CrtYd")
		)
		(pad "1" smd rect
			(at 0.40005 0)
			(size 0.4572 0.508)
			(layers "F.Cu" "F.Mask" "F.Paste")
			(net "FAN1_TACH_IN")
		)
		(pad "2" smd rect
			(at -0.40005 0)
			(size 0.4572 0.508)
			(layers "F.Cu" "F.Mask" "F.Paste")
			(net "FAN1_TACH")
		)
	)
)
